(kicad_pcb
	(version 20221018)
	(generator pcbnew)
	(general
    (thickness 1.518)
  )
	(paper "A4")
	(title_block
    (title "Kria K26 Devboard")
    (date "2024-03-26")
    (rev "1.2.5")
    (comment 1 "www.antmicro.com")
    (comment 2 "Antmicro Ltd.")
		(comment 9 "footprints 469-478 of 660")
	)
	(layers
    (0 "F.Cu" mixed)
    (1 "In1.Cu" power)
    (2 "In2.Cu" mixed)
    (3 "In3.Cu" power)
    (4 "In4.Cu" mixed)
    (5 "In5.Cu" power)
    (6 "In6.Cu" mixed)
    (31 "B.Cu" power)
    (32 "B.Adhes" user "B.Adhesive")
    (33 "F.Adhes" user "F.Adhesive")
    (34 "B.Paste" user)
    (35 "F.Paste" user)
    (36 "B.SilkS" user "B.Silkscreen")
    (37 "F.SilkS" user "F.Silkscreen")
    (38 "B.Mask" user)
    (39 "F.Mask" user)
    (40 "Dwgs.User" user "User.Drawings")
    (41 "Cmts.User" user "User.Comments")
    (42 "Eco1.User" user "User.Eco1")
    (43 "Eco2.User" user "User.Eco2")
    (44 "Edge.Cuts" user)
    (45 "Margin" user)
    (46 "B.CrtYd" user "B.Courtyard")
    (47 "F.CrtYd" user "F.Courtyard")
    (48 "B.Fab" user)
    (49 "F.Fab" user)
  )
	(footprint "kria-k26-devboard-footprints:R_0402_1005Metric" (layer "B.Cu")
    (at 116.54 89.4 180)
    (descr "Resistor SMD 0402")
    (tags "resistor SMD 0402")
    (property "Author" "Antmicro")
    (property "License" "Apache-2.0")
    (property "MPN" "CR0402-FX-2003GLF")
    (property "Manufacturer" "Bourns")
    (property "Sheetfile" "usb.kicad_sch")
    (property "Sheetname" "USB")
    (property "Tolerance" "1%")
    (property "Val" "200k")
    (property "ki_description" "200k resistor in 0402 package with 1% tolerance")
    (attr smd)
    (fp_text reference "R45" (at 0.926942 -0.38) (layer "B.SilkS")
        (effects (font (size 0.7 0.7) (thickness 0.15)) (justify left bottom mirror))
    )
    (fp_text value "R_200k_0402" (at 0 -1.4) (layer "B.Fab") hide
        (effects (font (size 0.7 0.7) (thickness 0.15)) (justify left bottom mirror))
    )
    (fp_text user "${REFERENCE}" (at -0.95 -3.168) (layer "B.Fab") hide
        (effects (font (size 0.7 0.7) (thickness 0.15)) (justify left bottom mirror))
    )
    (fp_text user "License: Apache-2.0" (at -0.95 -5.169) (layer "B.Fab") hide
        (effects (font (size 0.7 0.7) (thickness 0.15)) (justify left bottom mirror))
    )
    (fp_text user "Author: Antmicro" (at -0.95 -4.169) (layer "B.Fab") hide
        (effects (font (size 0.7 0.7) (thickness 0.15)) (justify left bottom mirror))
    )
    (fp_rect (start -0.93 0.47) (end 0.93 -0.47)
      (stroke (width 0.05) (type solid)) (fill none) (layer "B.CrtYd"))
    (fp_rect (start -0.5 0.25) (end 0.5 -0.25)
      (stroke (width 0.15) (type solid)) (fill none) (layer "B.Fab"))
    (pad "1" smd roundrect (at -0.485 0 180) (size 0.59 0.64) (layers "B.Cu" "B.Paste" "B.Mask") (roundrect_rratio 0.25)
      (net 1 "GND") (pintype "passive"))
    (pad "2" smd roundrect (at 0.485 0 180) (size 0.59 0.64) (layers "B.Cu" "B.Paste" "B.Mask") (roundrect_rratio 0.25)
      (net 648 "Net-(U17-SPI_D3{slash}PF25)") (pintype "passive"))
  )
	(footprint "kria-k26-devboard-footprints:R_0402_1005Metric" (layer "B.Cu")
    (at 116.606942 84.4 180)
    (descr "Resistor SMD 0402")
    (tags "resistor SMD 0402")
    (property "Author" "Antmicro")
    (property "License" "Apache-2.0")
    (property "MPN" "CR0402-FX-1002GLF")
    (property "Manufacturer" "Bourns")
    (property "Sheetfile" "usb.kicad_sch")
    (property "Sheetname" "USB")
    (property "Tolerance" "1%")
    (property "Val" "10k")
    (property "ki_description" "10k resistor in 0402 package with 1% tolerance")
    (attr smd)
    (fp_text reference "R46" (at 0.896942 -0.34) (layer "B.SilkS")
        (effects (font (size 0.7 0.7) (thickness 0.15)) (justify left bottom mirror))
    )
    (fp_text value "R_10k_0402" (at 0 -1.4) (layer "B.Fab") hide
        (effects (font (size 0.7 0.7) (thickness 0.15)) (justify left bottom mirror))
    )
    (fp_text user "${REFERENCE}" (at -0.95 -3.168) (layer "B.Fab") hide
        (effects (font (size 0.7 0.7) (thickness 0.15)) (justify left bottom mirror))
    )
    (fp_text user "Author: Antmicro" (at -0.95 -4.169) (layer "B.Fab") hide
        (effects (font (size 0.7 0.7) (thickness 0.15)) (justify left bottom mirror))
    )
    (fp_text user "License: Apache-2.0" (at -0.95 -5.169) (layer "B.Fab") hide
        (effects (font (size 0.7 0.7) (thickness 0.15)) (justify left bottom mirror))
    )
    (fp_rect (start -0.93 0.47) (end 0.93 -0.47)
      (stroke (width 0.05) (type solid)) (fill none) (layer "B.CrtYd"))
    (fp_rect (start -0.5 0.25) (end 0.5 -0.25)
      (stroke (width 0.15) (type solid)) (fill none) (layer "B.Fab"))
    (pad "1" smd roundrect (at -0.485 0 180) (size 0.59 0.64) (layers "B.Cu" "B.Paste" "B.Mask") (roundrect_rratio 0.25)
      (net 15 "PS_3V3") (pintype "passive"))
    (pad "2" smd roundrect (at 0.485 0 180) (size 0.59 0.64) (layers "B.Cu" "B.Paste" "B.Mask") (roundrect_rratio 0.25)
      (net 649 "Net-(U17-TEST1)") (pintype "passive"))
  )
	(footprint "kria-k26-devboard-footprints:R_0402_1005Metric" (layer "B.Cu")
    (at 116.606943 85.4 180)
    (descr "Resistor SMD 0402")
    (tags "resistor SMD 0402")
    (property "Author" "Antmicro")
    (property "License" "Apache-2.0")
    (property "MPN" "CR0402-FX-1002GLF")
    (property "Manufacturer" "Bourns")
    (property "Sheetfile" "usb.kicad_sch")
    (property "Sheetname" "USB")
    (property "Tolerance" "1%")
    (property "Val" "10k")
    (property "ki_description" "10k resistor in 0402 package with 1% tolerance")
    (attr smd)
    (fp_text reference "R48" (at 0.906943 -0.37) (layer "B.SilkS")
        (effects (font (size 0.7 0.7) (thickness 0.15)) (justify left bottom mirror))
    )
    (fp_text value "R_10k_0402" (at 0 -1.4) (layer "B.Fab") hide
        (effects (font (size 0.7 0.7) (thickness 0.15)) (justify left bottom mirror))
    )
    (fp_text user "Author: Antmicro" (at -0.95 -4.169) (layer "B.Fab") hide
        (effects (font (size 0.7 0.7) (thickness 0.15)) (justify left bottom mirror))
    )
    (fp_text user "License: Apache-2.0" (at -0.95 -5.169) (layer "B.Fab") hide
        (effects (font (size 0.7 0.7) (thickness 0.15)) (justify left bottom mirror))
    )
    (fp_text user "${REFERENCE}" (at -0.95 -3.168) (layer "B.Fab") hide
        (effects (font (size 0.7 0.7) (thickness 0.15)) (justify left bottom mirror))
    )
    (fp_rect (start -0.93 0.47) (end 0.93 -0.47)
      (stroke (width 0.05) (type solid)) (fill none) (layer "B.CrtYd"))
    (fp_rect (start -0.5 0.25) (end 0.5 -0.25)
      (stroke (width 0.15) (type solid)) (fill none) (layer "B.Fab"))
    (pad "1" smd roundrect (at -0.485 0 180) (size 0.59 0.64) (layers "B.Cu" "B.Paste" "B.Mask") (roundrect_rratio 0.25)
      (net 1 "GND") (pintype "passive"))
    (pad "2" smd roundrect (at 0.485 0 180) (size 0.59 0.64) (layers "B.Cu" "B.Paste" "B.Mask") (roundrect_rratio 0.25)
      (net 651 "Net-(U17-TEST3)") (pintype "passive"))
  )
	(footprint "kria-k26-devboard-footprints:R_0402_1005Metric" (layer "B.Cu")
    (at 127.666942 81.32486)
    (descr "Resistor SMD 0402")
    (tags "resistor SMD 0402")
    (property "Author" "Antmicro")
    (property "License" "Apache-2.0")
    (property "MPN" "CR0402-FX-2003GLF")
    (property "Manufacturer" "Bourns")
    (property "Sheetfile" "usb.kicad_sch")
    (property "Sheetname" "USB")
    (property "Tolerance" "1%")
    (property "Val" "200k")
    (property "ki_description" "200k resistor in 0402 package with 1% tolerance")
    (attr smd)
    (fp_text reference "R49" (at 1.043058 -0.61486 180) (layer "B.SilkS")
        (effects (font (size 0.7 0.7) (thickness 0.15)) (justify left bottom mirror))
    )
    (fp_text value "R_200k_0402" (at 0 -1.4 180) (layer "B.Fab") hide
        (effects (font (size 0.7 0.7) (thickness 0.15)) (justify left bottom mirror))
    )
    (fp_text user "License: Apache-2.0" (at -0.95 -5.169 180) (layer "B.Fab") hide
        (effects (font (size 0.7 0.7) (thickness 0.15)) (justify left bottom mirror))
    )
    (fp_text user "${REFERENCE}" (at -0.95 -3.168 180) (layer "B.Fab") hide
        (effects (font (size 0.7 0.7) (thickness 0.15)) (justify left bottom mirror))
    )
    (fp_text user "Author: Antmicro" (at -0.95 -4.169 180) (layer "B.Fab") hide
        (effects (font (size 0.7 0.7) (thickness 0.15)) (justify left bottom mirror))
    )
    (fp_rect (start -0.93 0.47) (end 0.93 -0.47)
      (stroke (width 0.05) (type solid)) (fill none) (layer "B.CrtYd"))
    (fp_rect (start -0.5 0.25) (end 0.5 -0.25)
      (stroke (width 0.15) (type solid)) (fill none) (layer "B.Fab"))
    (pad "1" smd roundrect (at -0.485 0) (size 0.59 0.64) (layers "B.Cu" "B.Paste" "B.Mask") (roundrect_rratio 0.25)
      (net 1 "GND") (pintype "passive"))
    (pad "2" smd roundrect (at 0.485 0) (size 0.59 0.64) (layers "B.Cu" "B.Paste" "B.Mask") (roundrect_rratio 0.25)
      (net 652 "Net-(U17-CFG_STRAP1)") (pintype "passive"))
  )
	(footprint "kria-k26-devboard-footprints:R_0402_1005Metric" (layer "B.Cu")
    (at 118.2 78.97 90)
    (descr "Resistor SMD 0402")
    (tags "resistor SMD 0402")
    (property "Author" "Antmicro")
    (property "License" "Apache-2.0")
    (property "MPN" "CR0402-FX-2003GLF")
    (property "Manufacturer" "Bourns")
    (property "Sheetfile" "usb.kicad_sch")
    (property "Sheetname" "USB")
    (property "Tolerance" "1%")
    (property "Val" "200k")
    (property "ki_description" "200k resistor in 0402 package with 1% tolerance")
    (attr smd)
    (fp_text reference "R55" (at 3.065 0.38 270) (layer "B.SilkS")
        (effects (font (size 0.7 0.7) (thickness 0.15)) (justify left bottom mirror))
    )
    (fp_text value "R_200k_0402" (at 0 -1.4 270) (layer "B.Fab") hide
        (effects (font (size 0.7 0.7) (thickness 0.15)) (justify left bottom mirror))
    )
    (fp_text user "Author: Antmicro" (at -0.95 -4.169 270) (layer "B.Fab") hide
        (effects (font (size 0.7 0.7) (thickness 0.15)) (justify left bottom mirror))
    )
    (fp_text user "License: Apache-2.0" (at -0.95 -5.169 270) (layer "B.Fab") hide
        (effects (font (size 0.7 0.7) (thickness 0.15)) (justify left bottom mirror))
    )
    (fp_text user "${REFERENCE}" (at -0.95 -3.168 270) (layer "B.Fab") hide
        (effects (font (size 0.7 0.7) (thickness 0.15)) (justify left bottom mirror))
    )
    (fp_rect (start -0.93 0.47) (end 0.93 -0.47)
      (stroke (width 0.05) (type solid)) (fill none) (layer "B.CrtYd"))
    (fp_rect (start -0.5 0.25) (end 0.5 -0.25)
      (stroke (width 0.15) (type solid)) (fill none) (layer "B.Fab"))
    (pad "1" smd roundrect (at -0.485 0 90) (size 0.59 0.64) (layers "B.Cu" "B.Paste" "B.Mask") (roundrect_rratio 0.25)
      (net 1 "GND") (pintype "passive"))
    (pad "2" smd roundrect (at 0.485 0 90) (size 0.59 0.64) (layers "B.Cu" "B.Paste" "B.Mask") (roundrect_rratio 0.25)
      (net 658 "Net-(U17-PF5)") (pintype "passive"))
  )
	(footprint "kria-k26-devboard-footprints:R_0402_1005Metric" (layer "B.Cu")
    (at 117.2 78.97 90)
    (descr "Resistor SMD 0402")
    (tags "resistor SMD 0402")
    (property "Author" "Antmicro")
    (property "License" "Apache-2.0")
    (property "MPN" "CR0402-FX-2003GLF")
    (property "Manufacturer" "Bourns")
    (property "Sheetfile" "usb.kicad_sch")
    (property "Sheetname" "USB")
    (property "Tolerance" "1%")
    (property "Val" "200k")
    (property "ki_description" "200k resistor in 0402 package with 1% tolerance")
    (attr smd)
    (fp_text reference "R57" (at 3.065 0.38 270) (layer "B.SilkS")
        (effects (font (size 0.7 0.7) (thickness 0.15)) (justify left bottom mirror))
    )
    (fp_text value "R_200k_0402" (at 0 -1.4 270) (layer "B.Fab") hide
        (effects (font (size 0.7 0.7) (thickness 0.15)) (justify left bottom mirror))
    )
    (fp_text user "License: Apache-2.0" (at -0.95 -5.169 270) (layer "B.Fab") hide
        (effects (font (size 0.7 0.7) (thickness 0.15)) (justify left bottom mirror))
    )
    (fp_text user "${REFERENCE}" (at -0.95 -3.168 270) (layer "B.Fab") hide
        (effects (font (size 0.7 0.7) (thickness 0.15)) (justify left bottom mirror))
    )
    (fp_text user "Author: Antmicro" (at -0.95 -4.169 270) (layer "B.Fab") hide
        (effects (font (size 0.7 0.7) (thickness 0.15)) (justify left bottom mirror))
    )
    (fp_rect (start -0.93 0.47) (end 0.93 -0.47)
      (stroke (width 0.05) (type solid)) (fill none) (layer "B.CrtYd"))
    (fp_rect (start -0.5 0.25) (end 0.5 -0.25)
      (stroke (width 0.15) (type solid)) (fill none) (layer "B.Fab"))
    (pad "1" smd roundrect (at -0.485 0 90) (size 0.59 0.64) (layers "B.Cu" "B.Paste" "B.Mask") (roundrect_rratio 0.25)
      (net 1 "GND") (pintype "passive"))
    (pad "2" smd roundrect (at 0.485 0 90) (size 0.59 0.64) (layers "B.Cu" "B.Paste" "B.Mask") (roundrect_rratio 0.25)
      (net 660 "Net-(U17-PF7)") (pintype "passive"))
  )
	(footprint "kria-k26-devboard-footprints:R_0402_1005Metric" (layer "B.Cu")
    (at 127.666943 88.55)
    (descr "Resistor SMD 0402")
    (tags "resistor SMD 0402")
    (property "Author" "Antmicro")
    (property "License" "Apache-2.0")
    (property "MPN" "CR0402-FX-2003GLF")
    (property "Manufacturer" "Bourns")
    (property "Sheetfile" "usb.kicad_sch")
    (property "Sheetname" "USB")
    (property "Tolerance" "1%")
    (property "Val" "200k")
    (property "ki_description" "200k resistor in 0402 package with 1% tolerance")
    (attr smd)
    (fp_text reference "R60" (at -0.906943 0.35 180) (layer "B.SilkS")
        (effects (font (size 0.7 0.7) (thickness 0.15)) (justify left bottom mirror))
    )
    (fp_text value "R_200k_0402" (at 0 -1.4 180) (layer "B.Fab") hide
        (effects (font (size 0.7 0.7) (thickness 0.15)) (justify left bottom mirror))
    )
    (fp_text user "Author: Antmicro" (at -0.95 -4.169 180) (layer "B.Fab") hide
        (effects (font (size 0.7 0.7) (thickness 0.15)) (justify left bottom mirror))
    )
    (fp_text user "License: Apache-2.0" (at -0.95 -5.169 180) (layer "B.Fab") hide
        (effects (font (size 0.7 0.7) (thickness 0.15)) (justify left bottom mirror))
    )
    (fp_text user "${REFERENCE}" (at -0.95 -3.168 180) (layer "B.Fab") hide
        (effects (font (size 0.7 0.7) (thickness 0.15)) (justify left bottom mirror))
    )
    (fp_rect (start -0.93 0.47) (end 0.93 -0.47)
      (stroke (width 0.05) (type solid)) (fill none) (layer "B.CrtYd"))
    (fp_rect (start -0.5 0.25) (end 0.5 -0.25)
      (stroke (width 0.15) (type solid)) (fill none) (layer "B.Fab"))
    (pad "1" smd roundrect (at -0.485 0) (size 0.59 0.64) (layers "B.Cu" "B.Paste" "B.Mask") (roundrect_rratio 0.25)
      (net 1 "GND") (pintype "passive"))
    (pad "2" smd roundrect (at 0.485 0) (size 0.59 0.64) (layers "B.Cu" "B.Paste" "B.Mask") (roundrect_rratio 0.25)
      (net 663 "Net-(U17-PF30)") (pintype "passive"))
  )
	(footprint "kria-k26-devboard-footprints:C_0402_1005Metric" (layer "B.Cu")
    (at 96.45 146.95 90)
    (descr "Capacitor SMD 0402")
    (tags "capacitor SMD 0402")
    (property "Author" "Antmicro")
    (property "Dielectric" "X5R")
    (property "License" "Apache-2.0")
    (property "MPN" "GRM155R61H104KE14D")
    (property "Manufacturer" "Murata")
    (property "Sheetfile" "reset.kicad_sch")
    (property "Sheetname" "Reset logic")
    (property "Val" "100n")
    (property "Voltage" "50V")
    (property "ki_description" " ")
    (attr smd)
    (fp_text reference "C135" (at 1.33 1.33 270) (layer "B.SilkS")
        (effects (font (size 0.7 0.7) (thickness 0.15)) (justify left bottom mirror))
    )
    (fp_text value "C_100n_0402" (at 0 -1.4 270) (layer "B.Fab") hide
        (effects (font (size 0.7 0.7) (thickness 0.15)) (justify left bottom mirror))
    )
    (fp_text user "License: Apache-2.0" (at -0.932 -5.17 270) (layer "B.Fab") hide
        (effects (font (size 0.7 0.7) (thickness 0.15)) (justify left bottom mirror))
    )
    (fp_text user "Author: Antmicro" (at -0.932 -4.17 270) (layer "B.Fab") hide
        (effects (font (size 0.7 0.7) (thickness 0.15)) (justify left bottom mirror))
    )
    (fp_text user "${REFERENCE}" (at -0.932 -3.168 270) (layer "B.Fab") hide
        (effects (font (size 0.7 0.7) (thickness 0.15)) (justify left bottom mirror))
    )
    (fp_rect (start -0.94 0.47) (end 0.94 -0.47)
      (stroke (width 0.05) (type solid)) (fill none) (layer "B.CrtYd"))
    (fp_rect (start -0.499 0.249) (end 0.499 -0.249)
      (stroke (width 0.15) (type solid)) (fill none) (layer "B.Fab"))
    (pad "1" smd roundrect (at -0.484 0 90) (size 0.59 0.64) (layers "B.Cu" "B.Paste" "B.Mask") (roundrect_rratio 0.25)
      (net 20 "PL_3V3") (pintype "passive"))
    (pad "2" smd roundrect (at 0.484 0 90) (size 0.59 0.64) (layers "B.Cu" "B.Paste" "B.Mask") (roundrect_rratio 0.25)
      (net 1 "GND") (pintype "passive"))
  )
	(footprint "kria-k26-devboard-footprints:C_0402_1005Metric" (layer "B.Cu")
    (at 96.725 140.575001 -90)
    (descr "Capacitor SMD 0402")
    (tags "capacitor SMD 0402")
    (property "Author" "Antmicro")
    (property "Dielectric" "")
    (property "License" "Apache-2.0")
    (property "MPN" "MC0402X473K160CT")
    (property "Manufacturer" "Multicomp")
    (property "Sheetfile" "reset.kicad_sch")
    (property "Sheetname" "Reset logic")
    (property "Val" "47n")
    (property "Voltage" "")
    (property "ki_description" " ")
    (attr smd)
    (fp_text reference "C130" (at -1.395001 0.605 90) (layer "B.SilkS")
        (effects (font (size 0.7 0.7) (thickness 0.15)) (justify left bottom mirror))
    )
    (fp_text value "C_47n_0402" (at 0 -1.4 90) (layer "B.Fab") hide
        (effects (font (size 0.7 0.7) (thickness 0.15)) (justify left bottom mirror))
    )
    (fp_text user "License: Apache-2.0" (at -0.932 -5.17 90) (layer "B.Fab") hide
        (effects (font (size 0.7 0.7) (thickness 0.15)) (justify left bottom mirror))
    )
    (fp_text user "${REFERENCE}" (at -0.932 -3.168 90) (layer "B.Fab") hide
        (effects (font (size 0.7 0.7) (thickness 0.15)) (justify left bottom mirror))
    )
    (fp_text user "Author: Antmicro" (at -0.932 -4.17 90) (layer "B.Fab") hide
        (effects (font (size 0.7 0.7) (thickness 0.15)) (justify left bottom mirror))
    )
    (fp_rect (start -0.94 0.47) (end 0.94 -0.47)
      (stroke (width 0.05) (type solid)) (fill none) (layer "B.CrtYd"))
    (fp_rect (start -0.499 0.249) (end 0.499 -0.249)
      (stroke (width 0.15) (type solid)) (fill none) (layer "B.Fab"))
    (pad "1" smd roundrect (at -0.484 0 270) (size 0.59 0.64) (layers "B.Cu" "B.Paste" "B.Mask") (roundrect_rratio 0.25)
      (net 246 "Net-(U32-CT)") (pintype "passive"))
    (pad "2" smd roundrect (at 0.484 0 270) (size 0.59 0.64) (layers "B.Cu" "B.Paste" "B.Mask") (roundrect_rratio 0.25)
      (net 1 "GND") (pintype "passive"))
  )
	(footprint "kria-k26-devboard-footprints:R_0402_1005Metric" (layer "B.Cu")
    (at 94.575 146.96 -90)
    (descr "Resistor SMD 0402")
    (tags "resistor SMD 0402")
    (property "Author" "Antmicro")
    (property "Current" "1A")
    (property "DNP" "DNP")
    (property "License" "Apache-2.0")
    (property "MPN" "ERJ2GE0R00X")
    (property "Manufacturer" "Panasonic")
    (property "Sheetfile" "reset.kicad_sch")
    (property "Sheetname" "Reset logic")
    (property "Tolerance" "")
    (property "Val" "0R")
    (property "dnp" "")
    (property "exclude_from_bom" "")
    (property "ki_description" "0R resistor in 0402 package with unspecified tolerance")
    (attr exclude_from_pos_files exclude_from_bom)
    (fp_text reference "R86" (at -1.01 0.585 90) (layer "B.SilkS")
        (effects (font (size 0.7 0.7) (thickness 0.15)) (justify left bottom mirror))
    )
    (fp_text value "R_0R_0402" (at 0 -1.4 90) (layer "B.Fab") hide
        (effects (font (size 0.7 0.7) (thickness 0.15)) (justify left bottom mirror))
    )
    (fp_text user "License: Apache-2.0" (at -0.95 -5.169 90) (layer "B.Fab") hide
        (effects (font (size 0.7 0.7) (thickness 0.15)) (justify left bottom mirror))
    )
    (fp_text user "${REFERENCE}" (at -0.95 -3.168 90) (layer "B.Fab") hide
        (effects (font (size 0.7 0.7) (thickness 0.15)) (justify left bottom mirror))
    )
    (fp_text user "Author: Antmicro" (at -0.95 -4.169 90) (layer "B.Fab") hide
        (effects (font (size 0.7 0.7) (thickness 0.15)) (justify left bottom mirror))
    )
    (fp_rect (start -0.93 0.47) (end 0.93 -0.47)
      (stroke (width 0.05) (type solid)) (fill none) (layer "B.CrtYd"))
    (fp_rect (start -0.5 0.25) (end 0.5 -0.25)
      (stroke (width 0.15) (type solid)) (fill none) (layer "B.Fab"))
    (pad "1" smd roundrect (at -0.485 0 270) (size 0.59 0.64) (layers "B.Cu" "B.Paste" "B.Mask") (roundrect_rratio 0.25)
      (net 129 "/Reset logic/HDA02") (pintype "passive"))
    (pad "2" smd roundrect (at 0.485 0 270) (size 0.59 0.64) (layers "B.Cu" "B.Paste" "B.Mask") (roundrect_rratio 0.25)
      (net 198 "/Camera interface/CAM0_RST") (pintype "passive"))
  )
)
